(kicad_pcb
	(version 20241229)
	(generator "pcbnew")
	(generator_version "9.0")
	(general
		(thickness 1.62)
		(legacy_teardrops no)
	)
	(paper "A4")
	(title_block
		(title "OCuLink to 10GbE adapter")
		(date "2026-02-23")
		(rev "1.1.0")
		(company "Antmicro Ltd")
		(comment 1 "www.antmicro.com")
		(comment 9 "footprints 468-472 of 510")
	)
	(layers
		(0 "F.Cu" signal)
		(4 "In1.Cu" signal)
		(6 "In2.Cu" signal)
		(8 "In3.Cu" signal)
		(10 "In4.Cu" signal)
		(12 "In5.Cu" signal)
		(14 "In6.Cu" signal)
		(2 "B.Cu" signal)
		(9 "F.Adhes" user "F.Adhesive")
		(11 "B.Adhes" user "B.Adhesive")
		(13 "F.Paste" user)
		(15 "B.Paste" user)
		(5 "F.SilkS" user "F.Silkscreen")
		(7 "B.SilkS" user "B.Silkscreen")
		(1 "F.Mask" user)
		(3 "B.Mask" user)
		(17 "Dwgs.User" user "User.Drawings")
		(19 "Cmts.User" user "User.Comments")
		(21 "Eco1.User" user "User.Eco1")
		(23 "Eco2.User" user "User.Eco2")
		(25 "Edge.Cuts" user)
		(27 "Margin" user)
		(31 "F.CrtYd" user "F.Courtyard")
		(29 "B.CrtYd" user "B.Courtyard")
		(35 "F.Fab" user)
		(33 "B.Fab" user)
	)
	(footprint "antmicro-footprints:R_0402_1005Metric"
		(layer "B.Cu")
		(at 73.75 90.8 90)
		(descr "Resistor SMD 0402")
		(tags "resistor SMD 0402")
		(property "Reference" "R35"
			(at -1.35 0.6 90)
			(layer "B.SilkS")
			(effects
				(font
					(size 0.7 0.7)
					(thickness 0.15)
				)
				(justify right top mirror)
			)
		)
		(property "Value" "R_10k_0402"
			(at -1.011843 -1.772046 90)
			(layer "B.Fab")
			(hide yes)
			(effects
				(font
					(size 0.7 0.7)
					(thickness 0.15)
				)
				(justify right top mirror)
			)
		)
		(property "Datasheet" "https://www.bourns.com/docs/product-datasheets/cr.pdf"
			(at 0 0 90)
			(layer "B.Fab")
			(hide yes)
			(effects
				(font
					(size 1.27 1.27)
					(thickness 0.15)
				)
				(justify mirror)
			)
		)
		(property "Description" "SMD Chip Resistor, 10 kohm, ± 1%, 62.5 mW, 0402 [1005 Metric], Thick Film, General Purpose"
			(at 0 0 90)
			(layer "B.Fab")
			(hide yes)
			(effects
				(font
					(size 1.27 1.27)
					(thickness 0.15)
				)
				(justify mirror)
			)
		)
		(property "MPN" "CR0402-FX-1002GLF"
			(at 0 0 90)
			(unlocked yes)
			(layer "B.Fab")
			(hide yes)
			(effects
				(font
					(size 1 1)
					(thickness 0.15)
				)
				(justify mirror)
			)
		)
		(property "Manufacturer" "Bourns"
			(at 0 0 90)
			(unlocked yes)
			(layer "B.Fab")
			(hide yes)
			(effects
				(font
					(size 1 1)
					(thickness 0.15)
				)
				(justify mirror)
			)
		)
		(property "License" "Apache-2.0"
			(at 0 0 90)
			(unlocked yes)
			(layer "B.Fab")
			(hide yes)
			(effects
				(font
					(size 1 1)
					(thickness 0.15)
				)
				(justify mirror)
			)
		)
		(property "Author" "Antmicro"
			(at 0 0 90)
			(unlocked yes)
			(layer "B.Fab")
			(hide yes)
			(effects
				(font
					(size 1 1)
					(thickness 0.15)
				)
				(justify mirror)
			)
		)
		(property "Val" "10k"
			(at 0 0 90)
			(unlocked yes)
			(layer "B.Fab")
			(hide yes)
			(effects
				(font
					(size 1 1)
					(thickness 0.15)
				)
				(justify mirror)
			)
		)
		(property "Tolerance" "1%"
			(at 0 0 90)
			(unlocked yes)
			(layer "B.Fab")
			(hide yes)
			(effects
				(font
					(size 1 1)
					(thickness 0.15)
				)
				(justify mirror)
			)
		)
		(sheetname "/Flash memory/")
		(sheetfile "flash-memory.kicad_sch")
		(attr smd)
		(fp_rect
			(start -0.925 0.47)
			(end 0.925 -0.47)
			(stroke
				(width 0.05)
				(type default)
			)
			(fill no)
			(layer "B.CrtYd")
		)
		(fp_rect
			(start -0.5 0.25)
			(end 0.5 -0.25)
			(stroke
				(width 0.15)
				(type solid)
			)
			(fill no)
			(layer "B.Fab")
		)
		(pad "1" smd roundrect
			(at -0.48 0 90)
			(size 0.59 0.64)
			(layers "B.Cu" "B.Mask" "B.Paste")
			(roundrect_rratio 0.25)
			(net 72 "/Flash memory/~{WP}")
			(pintype "passive")
		)
		(pad "2" smd roundrect
			(at 0.48 0 90)
			(size 0.59 0.64)
			(layers "B.Cu" "B.Mask" "B.Paste")
			(roundrect_rratio 0.25)
			(net 110 "/Flash memory/+3V3_FLASH")
			(pintype "passive")
		)
	)
	(footprint "antmicro-footprints:C_0402_1005Metric"
		(layer "B.Cu")
		(at 94.95 96.5 -90)
		(descr "Capacitor SMD 0402")
		(tags "capacitor SMD 0402")
		(property "Reference" "C130"
			(at 1.15 -3.35 90)
			(layer "B.SilkS")
			(effects
				(font
					(size 0.7 0.7)
					(thickness 0.15)
				)
				(justify right bottom mirror)
			)
		)
		(property "Value" "C_100n_0402"
			(at -1.022927 -2.155213 90)
			(layer "B.Fab")
			(hide yes)
			(effects
				(font
					(size 0.7 0.7)
					(thickness 0.15)
				)
				(justify left bottom mirror)
			)
		)
		(property "Datasheet" "https://www.murata.com/products/productdetail?partno=GRM155R61H104KE14%23"
			(at 0 0 90)
			(layer "B.Fab")
			(hide yes)
			(effects
				(font
					(size 1.27 1.27)
					(thickness 0.15)
				)
				(justify mirror)
			)
		)
		(property "Description" "SMD Multilayer Ceramic Capacitor, 0.1 µF, 50 V, 0402 [1005 Metric], ± 10%, X5R, GRM Series"
			(at 0 0 90)
			(layer "B.Fab")
			(hide yes)
			(effects
				(font
					(size 1.27 1.27)
					(thickness 0.15)
				)
				(justify mirror)
			)
		)
		(property "MPN" "GRM155R61H104KE14D"
			(at 0 0 270)
			(unlocked yes)
			(layer "B.Fab")
			(hide yes)
			(effects
				(font
					(size 1 1)
					(thickness 0.15)
				)
				(justify mirror)
			)
		)
		(property "Val" "100n"
			(at 0 0 270)
			(unlocked yes)
			(layer "B.Fab")
			(hide yes)
			(effects
				(font
					(size 1 1)
					(thickness 0.15)
				)
				(justify mirror)
			)
		)
		(property "Voltage" "50V"
			(at 0 0 270)
			(unlocked yes)
			(layer "B.Fab")
			(hide yes)
			(effects
				(font
					(size 1 1)
					(thickness 0.15)
				)
				(justify mirror)
			)
		)
		(property "Dielectric" "X5R"
			(at 0 0 270)
			(unlocked yes)
			(layer "B.Fab")
			(hide yes)
			(effects
				(font
					(size 1 1)
					(thickness 0.15)
				)
				(justify mirror)
			)
		)
		(property "Manufacturer" "Murata"
			(at 0 0 270)
			(unlocked yes)
			(layer "B.Fab")
			(hide yes)
			(effects
				(font
					(size 1 1)
					(thickness 0.15)
				)
				(justify mirror)
			)
		)
		(property "License" "Apache-2.0"
			(at 0 0 270)
			(unlocked yes)
			(layer "B.Fab")
			(hide yes)
			(effects
				(font
					(size 1 1)
					(thickness 0.15)
				)
				(justify mirror)
			)
		)
		(property "Author" "Antmicro"
			(at 0 0 270)
			(unlocked yes)
			(layer "B.Fab")
			(hide yes)
			(effects
				(font
					(size 1 1)
					(thickness 0.15)
				)
				(justify mirror)
			)
		)
		(sheetname "/X710-AT2 power/")
		(sheetfile "x710-at2-power.kicad_sch")
		(attr smd)
		(fp_rect
			(start -0.925 0.47)
			(end 0.925 -0.47)
			(stroke
				(width 0.05)
				(type default)
			)
			(fill no)
			(layer "B.CrtYd")
		)
		(fp_line
			(start -0.494 0.25)
			(end 0.504 0.25)
			(stroke
				(width 0.15)
				(type solid)
			)
			(layer "B.Fab")
		)
		(fp_line
			(start 0.504 0.25)
			(end 0.504 -0.248)
			(stroke
				(width 0.15)
				(type solid)
			)
			(layer "B.Fab")
		)
		(fp_line
			(start -0.494 -0.248)
			(end -0.494 0.25)
			(stroke
				(width 0.15)
				(type solid)
			)
			(layer "B.Fab")
		)
		(fp_line
			(start 0.504 -0.248)
			(end -0.494 -0.248)
			(stroke
				(width 0.15)
				(type solid)
			)
			(layer "B.Fab")
		)
		(pad "1" smd roundrect
			(at -0.48 0 270)
			(size 0.59 0.64)
			(layers "B.Cu" "B.Mask" "B.Paste")
			(roundrect_rratio 0.25)
			(net 28 "GND")
			(pintype "passive")
		)
		(pad "2" smd roundrect
			(at 0.48 0 270)
			(size 0.59 0.64)
			(layers "B.Cu" "B.Mask" "B.Paste")
			(roundrect_rratio 0.25)
			(net 7 "+3V3")
			(pintype "passive")
		)
	)
	(footprint "antmicro-footprints:C_0402_1005Metric"
		(layer "B.Cu")
		(at 89.225 100.15 90)
		(descr "Capacitor SMD 0402")
		(tags "capacitor SMD 0402")
		(property "Reference" "C90"
			(at 9.87 -0.39901 90)
			(layer "B.SilkS")
			(effects
				(font
					(size 0.7 0.7)
					(thickness 0.15)
				)
				(justify right top mirror)
			)
		)
		(property "Value" "C_1u_25V_0402"
			(at -1.022927 -2.155213 90)
			(layer "B.Fab")
			(hide yes)
			(effects
				(font
					(size 0.7 0.7)
					(thickness 0.15)
				)
				(justify right top mirror)
			)
		)
		(property "Datasheet" "https://www.murata.com/products/productdetail?partno=GRM155R61E105KE11%23"
			(at 0 0 90)
			(layer "B.Fab")
			(hide yes)
			(effects
				(font
					(size 1.27 1.27)
					(thickness 0.15)
				)
				(justify mirror)
			)
		)
		(property "Description" "SMD Multilayer Ceramic Capacitor, 1 µF, 25 V, 0402 [1005 Metric], ± 10%, X5R, GRM Series"
			(at 0 0 90)
			(layer "B.Fab")
			(hide yes)
			(effects
				(font
					(size 1.27 1.27)
					(thickness 0.15)
				)
				(justify mirror)
			)
		)
		(property "MPN" "GRM155R61E105KE11J"
			(at 0 0 90)
			(unlocked yes)
			(layer "B.Fab")
			(hide yes)
			(effects
				(font
					(size 1 1)
					(thickness 0.15)
				)
				(justify mirror)
			)
		)
		(property "Manufacturer" "Murata"
			(at 0 0 90)
			(unlocked yes)
			(layer "B.Fab")
			(hide yes)
			(effects
				(font
					(size 1 1)
					(thickness 0.15)
				)
				(justify mirror)
			)
		)
		(property "License" "Apache-2.0"
			(at 0 0 90)
			(unlocked yes)
			(layer "B.Fab")
			(hide yes)
			(effects
				(font
					(size 1 1)
					(thickness 0.15)
				)
				(justify mirror)
			)
		)
		(property "Author" "Antmicro"
			(at 0 0 90)
			(unlocked yes)
			(layer "B.Fab")
			(hide yes)
			(effects
				(font
					(size 1 1)
					(thickness 0.15)
				)
				(justify mirror)
			)
		)
		(property "Val" "1u"
			(at 0 0 90)
			(unlocked yes)
			(layer "B.Fab")
			(hide yes)
			(effects
				(font
					(size 1 1)
					(thickness 0.15)
				)
				(justify mirror)
			)
		)
		(property "Voltage" "25V"
			(at 0 0 90)
			(unlocked yes)
			(layer "B.Fab")
			(hide yes)
			(effects
				(font
					(size 1 1)
					(thickness 0.15)
				)
				(justify mirror)
			)
		)
		(property "Dielectric" "X5R"
			(at 0 0 90)
			(unlocked yes)
			(layer "B.Fab")
			(hide yes)
			(effects
				(font
					(size 1 1)
					(thickness 0.15)
				)
				(justify mirror)
			)
		)
		(sheetname "/X710-AT2 power/")
		(sheetfile "x710-at2-power.kicad_sch")
		(attr smd)
		(fp_rect
			(start -0.925 0.47)
			(end 0.925 -0.47)
			(stroke
				(width 0.05)
				(type default)
			)
			(fill no)
			(layer "B.CrtYd")
		)
		(fp_line
			(start 0.504 -0.248)
			(end -0.494 -0.248)
			(stroke
				(width 0.15)
				(type solid)
			)
			(layer "B.Fab")
		)
		(fp_line
			(start -0.494 -0.248)
			(end -0.494 0.25)
			(stroke
				(width 0.15)
				(type solid)
			)
			(layer "B.Fab")
		)
		(fp_line
			(start 0.504 0.25)
			(end 0.504 -0.248)
			(stroke
				(width 0.15)
				(type solid)
			)
			(layer "B.Fab")
		)
		(fp_line
			(start -0.494 0.25)
			(end 0.504 0.25)
			(stroke
				(width 0.15)
				(type solid)
			)
			(layer "B.Fab")
		)
		(pad "1" smd roundrect
			(at -0.48 0 90)
			(size 0.59 0.64)
			(layers "B.Cu" "B.Mask" "B.Paste")
			(roundrect_rratio 0.25)
			(net 28 "GND")
			(pintype "passive")
		)
		(pad "2" smd roundrect
			(at 0.48 0 90)
			(size 0.59 0.64)
			(layers "B.Cu" "B.Mask" "B.Paste")
			(roundrect_rratio 0.25)
			(net 1 "VCCA")
			(pintype "passive")
		)
	)
	(footprint "antmicro-footprints:C_0402_1005Metric"
		(layer "B.Cu")
		(at 76.95 101.35 180)
		(descr "Capacitor SMD 0402")
		(tags "capacitor SMD 0402")
		(property "Reference" "C102"
			(at 0.85 -0.4 0)
			(layer "B.SilkS")
			(effects
				(font
					(size 0.7 0.7)
					(thickness 0.15)
				)
				(justify left bottom mirror)
			)
		)
		(property "Value" "C_1u_25V_0402"
			(at -1.022927 -2.155213 0)
			(layer "B.Fab")
			(hide yes)
			(effects
				(font
					(size 0.7 0.7)
					(thickness 0.15)
				)
				(justify left bottom mirror)
			)
		)
		(property "Datasheet" "https://www.murata.com/products/productdetail?partno=GRM155R61E105KE11%23"
			(at 0 0 0)
			(layer "B.Fab")
			(hide yes)
			(effects
				(font
					(size 1.27 1.27)
					(thickness 0.15)
				)
				(justify mirror)
			)
		)
		(property "Description" "SMD Multilayer Ceramic Capacitor, 1 µF, 25 V, 0402 [1005 Metric], ± 10%, X5R, GRM Series"
			(at 0 0 0)
			(layer "B.Fab")
			(hide yes)
			(effects
				(font
					(size 1.27 1.27)
					(thickness 0.15)
				)
				(justify mirror)
			)
		)
		(property "MPN" "GRM155R61E105KE11J"
			(at 0 0 180)
			(unlocked yes)
			(layer "B.Fab")
			(hide yes)
			(effects
				(font
					(size 1 1)
					(thickness 0.15)
				)
				(justify mirror)
			)
		)
		(property "Manufacturer" "Murata"
			(at 0 0 180)
			(unlocked yes)
			(layer "B.Fab")
			(hide yes)
			(effects
				(font
					(size 1 1)
					(thickness 0.15)
				)
				(justify mirror)
			)
		)
		(property "License" "Apache-2.0"
			(at 0 0 180)
			(unlocked yes)
			(layer "B.Fab")
			(hide yes)
			(effects
				(font
					(size 1 1)
					(thickness 0.15)
				)
				(justify mirror)
			)
		)
		(property "Author" "Antmicro"
			(at 0 0 180)
			(unlocked yes)
			(layer "B.Fab")
			(hide yes)
			(effects
				(font
					(size 1 1)
					(thickness 0.15)
				)
				(justify mirror)
			)
		)
		(property "Val" "1u"
			(at 0 0 180)
			(unlocked yes)
			(layer "B.Fab")
			(hide yes)
			(effects
				(font
					(size 1 1)
					(thickness 0.15)
				)
				(justify mirror)
			)
		)
		(property "Voltage" "25V"
			(at 0 0 180)
			(unlocked yes)
			(layer "B.Fab")
			(hide yes)
			(effects
				(font
					(size 1 1)
					(thickness 0.15)
				)
				(justify mirror)
			)
		)
		(property "Dielectric" "X5R"
			(at 0 0 180)
			(unlocked yes)
			(layer "B.Fab")
			(hide yes)
			(effects
				(font
					(size 1 1)
					(thickness 0.15)
				)
				(justify mirror)
			)
		)
		(sheetname "/X710-AT2 power/")
		(sheetfile "x710-at2-power.kicad_sch")
		(attr smd)
		(fp_rect
			(start -0.925 0.47)
			(end 0.925 -0.47)
			(stroke
				(width 0.05)
				(type default)
			)
			(fill no)
			(layer "B.CrtYd")
		)
		(fp_line
			(start 0.504 0.25)
			(end 0.504 -0.248)
			(stroke
				(width 0.15)
				(type solid)
			)
			(layer "B.Fab")
		)
		(fp_line
			(start 0.504 -0.248)
			(end -0.494 -0.248)
			(stroke
				(width 0.15)
				(type solid)
			)
			(layer "B.Fab")
		)
		(fp_line
			(start -0.494 0.25)
			(end 0.504 0.25)
			(stroke
				(width 0.15)
				(type solid)
			)
			(layer "B.Fab")
		)
		(fp_line
			(start -0.494 -0.248)
			(end -0.494 0.25)
			(stroke
				(width 0.15)
				(type solid)
			)
			(layer "B.Fab")
		)
		(pad "1" smd roundrect
			(at -0.48 0 180)
			(size 0.59 0.64)
			(layers "B.Cu" "B.Mask" "B.Paste")
			(roundrect_rratio 0.25)
			(net 28 "GND")
			(pintype "passive")
		)
		(pad "2" smd roundrect
			(at 0.48 0 180)
			(size 0.59 0.64)
			(layers "B.Cu" "B.Mask" "B.Paste")
			(roundrect_rratio 0.25)
			(net 18 "+1V88")
			(pintype "passive")
		)
	)
	(footprint "antmicro-footprints:C_0603_1608Metric"
		(layer "B.Cu")
		(at 68.45 98.45 90)
		(descr "Capacitor SMD 0603")
		(tags "capacitor 0603")
		(property "Reference" "C100"
			(at -1.4 0.75 90)
			(layer "B.SilkS")
			(effects
				(font
					(size 0.7 0.7)
					(thickness 0.15)
				)
				(justify right top mirror)
			)
		)
		(property "Value" "C_10u_10V_X7R_0603"
			(at -1.42757 -1.770288 90)
			(layer "B.Fab")
			(hide yes)
			(effects
				(font
					(size 0.7 0.7)
					(thickness 0.15)
				)
				(justify right top mirror)
			)
		)
		(property "Datasheet" "https://www.murata.com/products/productdetail?partno=GRM188Z71A106KA73%23"
			(at 0 0 90)
			(layer "B.Fab")
			(hide yes)
			(effects
				(font
					(size 1.27 1.27)
					(thickness 0.15)
				)
				(justify mirror)
			)
		)
		(property "Description" "SMD Multilayer Ceramic Capacitor,  10µF, 10V, 0603, ±10%, X7R"
			(at 0 0 90)
			(layer "B.Fab")
			(hide yes)
			(effects
				(font
					(size 1.27 1.27)
					(thickness 0.15)
				)
				(justify mirror)
			)
		)
		(property "MPN" "GRM188Z71A106KA73D"
			(at 0 0 90)
			(unlocked yes)
			(layer "B.Fab")
			(hide yes)
			(effects
				(font
					(size 1 1)
					(thickness 0.15)
				)
				(justify mirror)
			)
		)
		(property "Val" "10u"
			(at 0 0 90)
			(unlocked yes)
			(layer "B.Fab")
			(hide yes)
			(effects
				(font
					(size 1 1)
					(thickness 0.15)
				)
				(justify mirror)
			)
		)
		(property "Voltage" "10V"
			(at 0 0 90)
			(unlocked yes)
			(layer "B.Fab")
			(hide yes)
			(effects
				(font
					(size 1 1)
					(thickness 0.15)
				)
				(justify mirror)
			)
		)
		(property "Dielectric" "X7R"
			(at 0 0 90)
			(unlocked yes)
			(layer "B.Fab")
			(hide yes)
			(effects
				(font
					(size 1 1)
					(thickness 0.15)
				)
				(justify mirror)
			)
		)
		(property "Manufacturer" "Murata"
			(at 0 0 90)
			(unlocked yes)
			(layer "B.Fab")
			(hide yes)
			(effects
				(font
					(size 1 1)
					(thickness 0.15)
				)
				(justify mirror)
			)
		)
		(property "License" "Apache-2.0"
			(at 0 0 90)
			(unlocked yes)
			(layer "B.Fab")
			(hide yes)
			(effects
				(font
					(size 1 1)
					(thickness 0.15)
				)
				(justify mirror)
			)
		)
		(property "Author" "Antmicro"
			(at 0 0 90)
			(unlocked yes)
			(layer "B.Fab")
			(hide yes)
			(effects
				(font
					(size 1 1)
					(thickness 0.15)
				)
				(justify mirror)
			)
		)
		(sheetname "/X710-AT2 power/")
		(sheetfile "x710-at2-power.kicad_sch")
		(attr smd)
		(fp_line
			(start -0.15 -0.4)
			(end 0.15 -0.4)
			(stroke
				(width 0.15)
				(type solid)
			)
			(layer "B.SilkS")
		)
		(fp_line
			(start -0.15 0.4)
			(end 0.15 0.4)
			(stroke
				(width 0.15)
				(type solid)
			)
			(layer "B.SilkS")
		)
		(fp_rect
			(start -1.25 0.65)
			(end 1.25 -0.65)
			(stroke
				(width 0.05)
				(type solid)
			)
			(fill no)
			(layer "B.CrtYd")
		)
		(fp_rect
			(start -0.8 0.4)
			(end 0.8 -0.4)
			(stroke
				(width 0.15)
				(type solid)
			)
			(fill no)
			(layer "B.Fab")
		)
		(pad "1" smd roundrect
			(at -0.7 0 90)
			(size 0.8 1)
			(layers "B.Cu" "B.Mask" "B.Paste")
			(roundrect_rratio 0.2)
			(net 28 "GND")
			(pintype "passive")
		)
		(pad "2" smd roundrect
			(at 0.7 0 90)
			(size 0.8 1)
			(layers "B.Cu" "B.Mask" "B.Paste")
			(roundrect_rratio 0.2)
			(net 18 "+1V88")
			(pintype "passive")
		)
	)
)
